(kicad_pcb
	(version 20260206)
	(generator "pcbnew")
	(generator_version "10.0")
	(general
		(thickness 1.6)
		(legacy_teardrops no)
	)
	(paper "A4")
	(title_block
		(title "04192023_DAF0TMB3IC0_F0TG_MB_C_brd_V02_OCP.brd")
		(comment 1 "Grand Teton / footprints 2766-2773 of 8354")
	)
	(layers
		(0 "F.Cu" signal "TOP")
		(4 "In1.Cu" signal "GND")
		(6 "In2.Cu" signal "IN1")
		(8 "In3.Cu" signal "GND1")
		(10 "In4.Cu" signal "IN2")
		(12 "In5.Cu" signal "GND2")
		(14 "In6.Cu" signal "IN3")
		(16 "In7.Cu" signal "GND3")
		(18 "In8.Cu" signal "VCC")
		(20 "In9.Cu" signal "VCC1")
		(22 "In10.Cu" signal "GND4")
		(24 "In11.Cu" signal "IN4")
		(26 "In12.Cu" signal "GND5")
		(28 "In13.Cu" signal "IN5")
		(30 "In14.Cu" signal "GND6")
		(32 "In15.Cu" signal "IN6")
		(34 "In16.Cu" signal "GND7")
		(2 "B.Cu" signal "BOTTOM")
		(9 "F.Adhes" user "F.Adhesive")
		(11 "B.Adhes" user "B.Adhesive")
		(13 "F.Paste" user "Package Geometry/Pastemask Top")
		(15 "B.Paste" user "Package Geometry/Pastemask Bottom")
		(5 "F.SilkS" user "Ref Des/Silkscreen Top")
		(7 "B.SilkS" user "Ref Des/Silkscreen Bottom")
		(1 "F.Mask" user "Board Geometry/Soldermask Top")
		(3 "B.Mask" user "Board Geometry/Soldermask Bottom")
		(17 "Dwgs.User" user "User.Drawings")
		(19 "Cmts.User" user "User.Comments")
		(21 "Eco1.User" user "User.Eco1")
		(23 "Eco2.User" user "User.Eco2")
		(25 "Edge.Cuts" user "Board Geometry/Outline")
		(27 "Margin" user)
		(31 "F.CrtYd" user "Package Geometry/Place Bound Top")
		(29 "B.CrtYd" user "Package Geometry/Place Bound Bottom")
		(35 "F.Fab" user "Ref Des/Assembly Top")
		(33 "B.Fab" user "Ref Des/Assembly Bottom")
	)
	(footprint ""
		(layer "F.Cu")
		(at 36.640262 -419.249098 -90)
		(property "Reference" "R3288"
			(at 0 0 270)
			(layer "F.SilkS")
			(hide yes)
			(effects
				(font
					(size 1.27 1.27)
				)
			)
		)
		(property "Value" ""
			(at 0 0 270)
			(layer "F.Fab")
			(effects
				(font
					(size 1.27 1.27)
				)
			)
		)
		(duplicate_pad_numbers_are_jumpers no)
		(fp_line
			(start -0.7874 0.4064)
			(end -0.7874 -0.4064)
			(stroke
				(width 0.1524)
				(type default)
			)
			(layer "F.SilkS")
		)
		(fp_line
			(start 0.7874 0.4064)
			(end -0.7874 0.4064)
			(stroke
				(width 0.1524)
				(type default)
			)
			(layer "F.SilkS")
		)
		(fp_line
			(start -0.7874 -0.4064)
			(end 0.7874 -0.4064)
			(stroke
				(width 0.1524)
				(type default)
			)
			(layer "F.SilkS")
		)
		(fp_line
			(start 0.7874 -0.4064)
			(end 0.7874 0.4064)
			(stroke
				(width 0.1524)
				(type default)
			)
			(layer "F.SilkS")
		)
		(fp_line
			(start -0.67945 0.3048)
			(end -0.67945 -0.305054)
			(stroke
				(width 0.1)
				(type default)
			)
			(layer "F.Fab")
		)
		(fp_line
			(start -0.12065 0.3048)
			(end -0.67945 0.3048)
			(stroke
				(width 0.1)
				(type default)
			)
			(layer "F.Fab")
		)
		(fp_line
			(start 0.120396 0.3048)
			(end 0.120396 0.2794)
			(stroke
				(width 0.1)
				(type default)
			)
			(layer "F.Fab")
		)
		(fp_line
			(start 0.67945 0.3048)
			(end 0.120396 0.3048)
			(stroke
				(width 0.1)
				(type default)
			)
			(layer "F.Fab")
		)
		(fp_line
			(start -0.12065 0.2794)
			(end -0.12065 0.3048)
			(stroke
				(width 0.1)
				(type default)
			)
			(layer "F.Fab")
		)
		(fp_line
			(start 0.120396 0.2794)
			(end -0.12065 0.2794)
			(stroke
				(width 0.1)
				(type default)
			)
			(layer "F.Fab")
		)
		(fp_line
			(start -0.12065 -0.2794)
			(end 0.12065 -0.2794)
			(stroke
				(width 0.1)
				(type default)
			)
			(layer "F.Fab")
		)
		(fp_line
			(start 0.12065 -0.2794)
			(end 0.12065 -0.3048)
			(stroke
				(width 0.1)
				(type default)
			)
			(layer "F.Fab")
		)
		(fp_line
			(start 0.12065 -0.3048)
			(end 0.67945 -0.3048)
			(stroke
				(width 0.1)
				(type default)
			)
			(layer "F.Fab")
		)
		(fp_line
			(start 0.67945 -0.3048)
			(end 0.67945 0.3048)
			(stroke
				(width 0.1)
				(type default)
			)
			(layer "F.Fab")
		)
		(fp_line
			(start -0.67945 -0.305054)
			(end -0.12065 -0.305054)
			(stroke
				(width 0.1)
				(type default)
			)
			(layer "F.Fab")
		)
		(fp_line
			(start -0.12065 -0.305054)
			(end -0.12065 -0.2794)
			(stroke
				(width 0.1)
				(type default)
			)
			(layer "F.Fab")
		)
		(pad "1" smd circle
			(at -0.40005 0 270)
			(size 0 0)
			(layers "F.Cu" "F.Mask" "F.Paste")
			(net "FM_P2E_SWA")
		)
		(pad "2" smd circle
			(at 0.40005 0 270)
			(size 0 0)
			(layers "F.Cu" "F.Mask" "F.Paste")
			(net "GND")
		)
	)
	(footprint ""
		(layer "F.Cu")
		(at 444.457582 -53.188108 90)
		(property "Reference" "PC2263"
			(at 0 0 90)
			(layer "F.SilkS")
			(hide yes)
			(effects
				(font
					(size 1.27 1.27)
				)
			)
		)
		(property "Value" ""
			(at 0 0 90)
			(layer "F.Fab")
			(effects
				(font
					(size 1.27 1.27)
				)
			)
		)
		(duplicate_pad_numbers_are_jumpers no)
		(fp_line
			(start 1.524 -0.762)
			(end 1.524 0.762)
			(stroke
				(width 0.1524)
				(type default)
			)
			(layer "F.SilkS")
		)
		(fp_line
			(start -1.524 -0.762)
			(end 1.524 -0.762)
			(stroke
				(width 0.1524)
				(type default)
			)
			(layer "F.SilkS")
		)
		(fp_line
			(start 1.524 0.762)
			(end -1.524 0.762)
			(stroke
				(width 0.1524)
				(type default)
			)
			(layer "F.SilkS")
		)
		(fp_line
			(start -1.524 0.762)
			(end -1.524 -0.762)
			(stroke
				(width 0.1524)
				(type default)
			)
			(layer "F.SilkS")
		)
		(fp_line
			(start 1.1049 -0.724916)
			(end -1.1049 -0.724916)
			(stroke
				(width 0.1)
				(type default)
			)
			(layer "F.Fab")
		)
		(fp_line
			(start -1.1049 -0.724916)
			(end -1.1049 0.724916)
			(stroke
				(width 0.1)
				(type default)
			)
			(layer "F.Fab")
		)
		(fp_line
			(start 1.1049 0.724916)
			(end 1.1049 -0.724916)
			(stroke
				(width 0.1)
				(type default)
			)
			(layer "F.Fab")
		)
		(fp_line
			(start -1.1049 0.724916)
			(end 1.1049 0.724916)
			(stroke
				(width 0.1)
				(type default)
			)
			(layer "F.Fab")
		)
		(pad "1" smd rect
			(at -0.889 0 270)
			(size 1.016 1.27)
			(layers "F.Cu" "F.Mask" "F.Paste")
			(net "SW_P3V3_AUX_FLT")
		)
		(pad "2" smd rect
			(at 0.889 0 270)
			(size 1.016 1.27)
			(layers "F.Cu" "F.Mask" "F.Paste")
			(net "GND")
		)
	)
	(footprint ""
		(layer "F.Cu")
		(at 38.666928 -351.372932 -90)
		(property "Reference" "PC631"
			(at 0 0 270)
			(layer "F.SilkS")
			(hide yes)
			(effects
				(font
					(size 1.27 1.27)
				)
			)
		)
		(property "Value" ""
			(at 0 0 270)
			(layer "F.Fab")
			(effects
				(font
					(size 1.27 1.27)
				)
			)
		)
		(duplicate_pad_numbers_are_jumpers no)
		(fp_line
			(start -0.7874 0.4064)
			(end -0.7874 -0.4064)
			(stroke
				(width 0.1524)
				(type default)
			)
			(layer "F.SilkS")
		)
		(fp_line
			(start 0.7874 0.4064)
			(end -0.7874 0.4064)
			(stroke
				(width 0.1524)
				(type default)
			)
			(layer "F.SilkS")
		)
		(fp_line
			(start -0.7874 -0.4064)
			(end 0.7874 -0.4064)
			(stroke
				(width 0.1524)
				(type default)
			)
			(layer "F.SilkS")
		)
		(fp_line
			(start 0.7874 -0.4064)
			(end 0.7874 0.4064)
			(stroke
				(width 0.1524)
				(type default)
			)
			(layer "F.SilkS")
		)
		(fp_line
			(start -0.67945 0.3048)
			(end -0.67945 -0.305054)
			(stroke
				(width 0.1)
				(type default)
			)
			(layer "F.Fab")
		)
		(fp_line
			(start -0.12065 0.3048)
			(end -0.67945 0.3048)
			(stroke
				(width 0.1)
				(type default)
			)
			(layer "F.Fab")
		)
		(fp_line
			(start 0.120396 0.3048)
			(end 0.120396 0.2794)
			(stroke
				(width 0.1)
				(type default)
			)
			(layer "F.Fab")
		)
		(fp_line
			(start 0.67945 0.3048)
			(end 0.120396 0.3048)
			(stroke
				(width 0.1)
				(type default)
			)
			(layer "F.Fab")
		)
		(fp_line
			(start -0.12065 0.2794)
			(end -0.12065 0.3048)
			(stroke
				(width 0.1)
				(type default)
			)
			(layer "F.Fab")
		)
		(fp_line
			(start 0.120396 0.2794)
			(end -0.12065 0.2794)
			(stroke
				(width 0.1)
				(type default)
			)
			(layer "F.Fab")
		)
		(fp_line
			(start -0.12065 -0.2794)
			(end 0.12065 -0.2794)
			(stroke
				(width 0.1)
				(type default)
			)
			(layer "F.Fab")
		)
		(fp_line
			(start 0.12065 -0.2794)
			(end 0.12065 -0.3048)
			(stroke
				(width 0.1)
				(type default)
			)
			(layer "F.Fab")
		)
		(fp_line
			(start 0.12065 -0.3048)
			(end 0.67945 -0.3048)
			(stroke
				(width 0.1)
				(type default)
			)
			(layer "F.Fab")
		)
		(fp_line
			(start 0.67945 -0.3048)
			(end 0.67945 0.3048)
			(stroke
				(width 0.1)
				(type default)
			)
			(layer "F.Fab")
		)
		(fp_line
			(start -0.67945 -0.305054)
			(end -0.12065 -0.305054)
			(stroke
				(width 0.1)
				(type default)
			)
			(layer "F.Fab")
		)
		(fp_line
			(start -0.12065 -0.305054)
			(end -0.12065 -0.2794)
			(stroke
				(width 0.1)
				(type default)
			)
			(layer "F.Fab")
		)
		(pad "1" smd circle
			(at -0.40005 0 270)
			(size 0 0)
			(layers "F.Cu" "F.Mask" "F.Paste")
			(net "SW_PVDDIO_P1_BOOT3_R")
		)
		(pad "2" smd circle
			(at 0.40005 0 270)
			(size 0 0)
			(layers "F.Cu" "F.Mask" "F.Paste")
			(net "SW_PVDDIO_P1_BOOTR3")
		)
	)
	(footprint ""
		(layer "F.Cu")
		(at 450.508878 -397.562578 -90)
		(property "Reference" "PC6551_09P0_2"
			(at 0 0 270)
			(layer "F.SilkS")
			(hide yes)
			(effects
				(font
					(size 1.27 1.27)
				)
			)
		)
		(property "Value" ""
			(at 0 0 270)
			(layer "F.Fab")
			(effects
				(font
					(size 1.27 1.27)
				)
			)
		)
		(duplicate_pad_numbers_are_jumpers no)
		(fp_line
			(start -0.7874 0.4064)
			(end -0.7874 -0.4064)
			(stroke
				(width 0.1524)
				(type default)
			)
			(layer "F.SilkS")
		)
		(fp_line
			(start 0.7874 0.4064)
			(end -0.7874 0.4064)
			(stroke
				(width 0.1524)
				(type default)
			)
			(layer "F.SilkS")
		)
		(fp_line
			(start -0.7874 -0.4064)
			(end 0.7874 -0.4064)
			(stroke
				(width 0.1524)
				(type default)
			)
			(layer "F.SilkS")
		)
		(fp_line
			(start 0.7874 -0.4064)
			(end 0.7874 0.4064)
			(stroke
				(width 0.1524)
				(type default)
			)
			(layer "F.SilkS")
		)
		(fp_line
			(start -0.67945 0.3048)
			(end -0.67945 -0.305054)
			(stroke
				(width 0.1)
				(type default)
			)
			(layer "F.Fab")
		)
		(fp_line
			(start -0.12065 0.3048)
			(end -0.67945 0.3048)
			(stroke
				(width 0.1)
				(type default)
			)
			(layer "F.Fab")
		)
		(fp_line
			(start 0.120396 0.3048)
			(end 0.120396 0.2794)
			(stroke
				(width 0.1)
				(type default)
			)
			(layer "F.Fab")
		)
		(fp_line
			(start 0.67945 0.3048)
			(end 0.120396 0.3048)
			(stroke
				(width 0.1)
				(type default)
			)
			(layer "F.Fab")
		)
		(fp_line
			(start -0.12065 0.2794)
			(end -0.12065 0.3048)
			(stroke
				(width 0.1)
				(type default)
			)
			(layer "F.Fab")
		)
		(fp_line
			(start 0.120396 0.2794)
			(end -0.12065 0.2794)
			(stroke
				(width 0.1)
				(type default)
			)
			(layer "F.Fab")
		)
		(fp_line
			(start -0.12065 -0.2794)
			(end 0.12065 -0.2794)
			(stroke
				(width 0.1)
				(type default)
			)
			(layer "F.Fab")
		)
		(fp_line
			(start 0.12065 -0.2794)
			(end 0.12065 -0.3048)
			(stroke
				(width 0.1)
				(type default)
			)
			(layer "F.Fab")
		)
		(fp_line
			(start 0.12065 -0.3048)
			(end 0.67945 -0.3048)
			(stroke
				(width 0.1)
				(type default)
			)
			(layer "F.Fab")
		)
		(fp_line
			(start 0.67945 -0.3048)
			(end 0.67945 0.3048)
			(stroke
				(width 0.1)
				(type default)
			)
			(layer "F.Fab")
		)
		(fp_line
			(start -0.67945 -0.305054)
			(end -0.12065 -0.305054)
			(stroke
				(width 0.1)
				(type default)
			)
			(layer "F.Fab")
		)
		(fp_line
			(start -0.12065 -0.305054)
			(end -0.12065 -0.2794)
			(stroke
				(width 0.1)
				(type default)
			)
			(layer "F.Fab")
		)
		(pad "1" smd circle
			(at -0.40005 0 270)
			(size 0 0)
			(layers "F.Cu" "F.Mask" "F.Paste")
			(net "P0V9_RETIMER_CPU0_PVCC")
		)
		(pad "2" smd circle
			(at 0.40005 0 270)
			(size 0 0)
			(layers "F.Cu" "F.Mask" "F.Paste")
			(net "GND")
		)
	)
	(footprint ""
		(layer "F.Cu")
		(at 304.682906 -416.899344 -90)
		(property "Reference" "C6501"
			(at 0 0 270)
			(layer "F.SilkS")
			(hide yes)
			(effects
				(font
					(size 1.27 1.27)
				)
			)
		)
		(property "Value" ""
			(at 0 0 270)
			(layer "F.Fab")
			(effects
				(font
					(size 1.27 1.27)
				)
			)
		)
		(duplicate_pad_numbers_are_jumpers no)
		(fp_line
			(start -0.299974 0.150114)
			(end -0.299974 -0.150114)
			(stroke
				(width 0.1)
				(type default)
			)
			(layer "F.Fab")
		)
		(fp_line
			(start 0.299974 0.150114)
			(end -0.299974 0.150114)
			(stroke
				(width 0.1)
				(type default)
			)
			(layer "F.Fab")
		)
		(fp_line
			(start -0.299974 -0.150114)
			(end 0.299974 -0.150114)
			(stroke
				(width 0.1)
				(type default)
			)
			(layer "F.Fab")
		)
		(fp_line
			(start 0.299974 -0.150114)
			(end 0.299974 0.150114)
			(stroke
				(width 0.1)
				(type default)
			)
			(layer "F.Fab")
		)
		(pad "1" smd rect
			(at -0.2667 0 270)
			(size 0.3048 0.381)
			(layers "F.Cu" "F.Mask" "F.Paste")
			(net "P5E_CPU0_P0_TX_BUF_C_DP<0>")
		)
		(pad "2" smd rect
			(at 0.2667 0 270)
			(size 0.3048 0.381)
			(layers "F.Cu" "F.Mask" "F.Paste")
			(net "P5E_CPU0_P0_TX_BUF_DP<0>")
		)
	)
	(footprint ""
		(layer "F.Cu")
		(at 142.155672 -387.764274)
		(property "Reference" "R619"
			(at 0 0 0)
			(layer "F.SilkS")
			(hide yes)
			(effects
				(font
					(size 1.27 1.27)
				)
			)
		)
		(property "Value" ""
			(at 0 0 0)
			(layer "F.Fab")
			(effects
				(font
					(size 1.27 1.27)
				)
			)
		)
		(duplicate_pad_numbers_are_jumpers no)
		(fp_line
			(start -0.32512 -0.175006)
			(end 0.32512 -0.175006)
			(stroke
				(width 0.1)
				(type default)
			)
			(layer "F.Fab")
		)
		(fp_line
			(start -0.32512 0.175006)
			(end -0.32512 -0.175006)
			(stroke
				(width 0.1)
				(type default)
			)
			(layer "F.Fab")
		)
		(fp_line
			(start 0.32512 -0.175006)
			(end 0.32512 0.175006)
			(stroke
				(width 0.1)
				(type default)
			)
			(layer "F.Fab")
		)
		(fp_line
			(start 0.32512 0.175006)
			(end -0.32512 0.175006)
			(stroke
				(width 0.1)
				(type default)
			)
			(layer "F.Fab")
		)
		(pad "1" smd rect
			(at -0.2667 0)
			(size 0.3048 0.381)
			(layers "F.Cu" "F.Mask" "F.Paste")
			(net "CLK_100M_RETIMER_CPU1_P2_R_DP")
		)
		(pad "2" smd rect
			(at 0.2667 0 180)
			(size 0.3048 0.381)
			(layers "F.Cu" "F.Mask" "F.Paste")
			(net "CLK_100M_RETIMER_CPU1_P2_DP")
		)
	)
	(footprint ""
		(layer "F.Cu")
		(at 455.617834 -93.437964)
		(property "Reference" "R3231"
			(at 0 0 0)
			(layer "F.SilkS")
			(hide yes)
			(effects
				(font
					(size 1.27 1.27)
				)
			)
		)
		(property "Value" ""
			(at 0 0 0)
			(layer "F.Fab")
			(effects
				(font
					(size 1.27 1.27)
				)
			)
		)
		(duplicate_pad_numbers_are_jumpers no)
		(fp_line
			(start -0.7874 -0.4064)
			(end 0.7874 -0.4064)
			(stroke
				(width 0.1524)
				(type default)
			)
			(layer "F.SilkS")
		)
		(fp_line
			(start -0.7874 0.4064)
			(end -0.7874 -0.4064)
			(stroke
				(width 0.1524)
				(type default)
			)
			(layer "F.SilkS")
		)
		(fp_line
			(start 0.7874 -0.4064)
			(end 0.7874 0.4064)
			(stroke
				(width 0.1524)
				(type default)
			)
			(layer "F.SilkS")
		)
		(fp_line
			(start 0.7874 0.4064)
			(end -0.7874 0.4064)
			(stroke
				(width 0.1524)
				(type default)
			)
			(layer "F.SilkS")
		)
		(fp_line
			(start -0.67945 -0.305054)
			(end -0.12065 -0.305054)
			(stroke
				(width 0.1)
				(type default)
			)
			(layer "F.Fab")
		)
		(fp_line
			(start -0.67945 0.3048)
			(end -0.67945 -0.305054)
			(stroke
				(width 0.1)
				(type default)
			)
			(layer "F.Fab")
		)
		(fp_line
			(start -0.12065 -0.305054)
			(end -0.12065 -0.2794)
			(stroke
				(width 0.1)
				(type default)
			)
			(layer "F.Fab")
		)
		(fp_line
			(start -0.12065 -0.2794)
			(end 0.12065 -0.2794)
			(stroke
				(width 0.1)
				(type default)
			)
			(layer "F.Fab")
		)
		(fp_line
			(start -0.12065 0.2794)
			(end -0.12065 0.3048)
			(stroke
				(width 0.1)
				(type default)
			)
			(layer "F.Fab")
		)
		(fp_line
			(start -0.12065 0.3048)
			(end -0.67945 0.3048)
			(stroke
				(width 0.1)
				(type default)
			)
			(layer "F.Fab")
		)
		(fp_line
			(start 0.120396 0.2794)
			(end -0.12065 0.2794)
			(stroke
				(width 0.1)
				(type default)
			)
			(layer "F.Fab")
		)
		(fp_line
			(start 0.120396 0.3048)
			(end 0.120396 0.2794)
			(stroke
				(width 0.1)
				(type default)
			)
			(layer "F.Fab")
		)
		(fp_line
			(start 0.12065 -0.3048)
			(end 0.67945 -0.3048)
			(stroke
				(width 0.1)
				(type default)
			)
			(layer "F.Fab")
		)
		(fp_line
			(start 0.12065 -0.2794)
			(end 0.12065 -0.3048)
			(stroke
				(width 0.1)
				(type default)
			)
			(layer "F.Fab")
		)
		(fp_line
			(start 0.67945 -0.3048)
			(end 0.67945 0.3048)
			(stroke
				(width 0.1)
				(type default)
			)
			(layer "F.Fab")
		)
		(fp_line
			(start 0.67945 0.3048)
			(end 0.120396 0.3048)
			(stroke
				(width 0.1)
				(type default)
			)
			(layer "F.Fab")
		)
		(pad "1" smd circle
			(at -0.40005 0)
			(size 0 0)
			(layers "F.Cu" "F.Mask" "F.Paste")
			(net "OCP_SFF_AUX_PWR_EN")
		)
		(pad "2" smd circle
			(at 0.40005 0)
			(size 0 0)
			(layers "F.Cu" "F.Mask" "F.Paste")
			(net "OCP_SFF_AUX_PWR_EN_R2")
		)
	)
	(footprint ""
		(layer "F.Cu")
		(at 151.254206 -191.35471 -90)
		(property "Reference" "R3200"
			(at 0 0 270)
			(layer "F.SilkS")
			(hide yes)
			(effects
				(font
					(size 1.27 1.27)
				)
			)
		)
		(property "Value" ""
			(at 0 0 270)
			(layer "F.Fab")
			(effects
				(font
					(size 1.27 1.27)
				)
			)
		)
		(duplicate_pad_numbers_are_jumpers no)
		(fp_line
			(start -0.7874 0.4064)
			(end -0.7874 0.073406)
			(stroke
				(width 0.1524)
				(type default)
			)
			(layer "F.SilkS")
		)
		(fp_line
			(start 0.7874 0.4064)
			(end -0.7874 0.4064)
			(stroke
				(width 0.1524)
				(type default)
			)
			(layer "F.SilkS")
		)
		(fp_line
			(start 0.7874 -0.053594)
			(end 0.7874 0.4064)
			(stroke
				(width 0.1524)
				(type default)
			)
			(layer "F.SilkS")
		)
		(fp_line
			(start -0.41529 -0.4064)
			(end 0.42291 -0.4064)
			(stroke
				(width 0.1524)
				(type default)
			)
			(layer "F.SilkS")
		)
		(fp_line
			(start -0.67945 0.3048)
			(end -0.67945 -0.305054)
			(stroke
				(width 0.1)
				(type default)
			)
			(layer "F.Fab")
		)
		(fp_line
			(start -0.12065 0.3048)
			(end -0.67945 0.3048)
			(stroke
				(width 0.1)
				(type default)
			)
			(layer "F.Fab")
		)
		(fp_line
			(start 0.120396 0.3048)
			(end 0.120396 0.2794)
			(stroke
				(width 0.1)
				(type default)
			)
			(layer "F.Fab")
		)
		(fp_line
			(start 0.67945 0.3048)
			(end 0.120396 0.3048)
			(stroke
				(width 0.1)
				(type default)
			)
			(layer "F.Fab")
		)
		(fp_line
			(start -0.12065 0.2794)
			(end -0.12065 0.3048)
			(stroke
				(width 0.1)
				(type default)
			)
			(layer "F.Fab")
		)
		(fp_line
			(start 0.120396 0.2794)
			(end -0.12065 0.2794)
			(stroke
				(width 0.1)
				(type default)
			)
			(layer "F.Fab")
		)
		(fp_line
			(start -0.12065 -0.2794)
			(end 0.12065 -0.2794)
			(stroke
				(width 0.1)
				(type default)
			)
			(layer "F.Fab")
		)
		(fp_line
			(start 0.12065 -0.2794)
			(end 0.12065 -0.3048)
			(stroke
				(width 0.1)
				(type default)
			)
			(layer "F.Fab")
		)
		(fp_line
			(start 0.12065 -0.3048)
			(end 0.67945 -0.3048)
			(stroke
				(width 0.1)
				(type default)
			)
			(layer "F.Fab")
		)
		(fp_line
			(start 0.67945 -0.3048)
			(end 0.67945 0.3048)
			(stroke
				(width 0.1)
				(type default)
			)
			(layer "F.Fab")
		)
		(fp_line
			(start -0.67945 -0.305054)
			(end -0.12065 -0.305054)
			(stroke
				(width 0.1)
				(type default)
			)
			(layer "F.Fab")
		)
		(fp_line
			(start -0.12065 -0.305054)
			(end -0.12065 -0.2794)
			(stroke
				(width 0.1)
				(type default)
			)
			(layer "F.Fab")
		)
		(pad "1" smd circle
			(at -0.40005 0 270)
			(size 0 0)
			(layers "F.Cu" "F.Mask" "F.Paste")
			(net "CLK_100M_CPU1_CLK05_R_DP")
		)
		(pad "2" smd circle
			(at 0.40005 0 270)
			(size 0 0)
			(layers "F.Cu" "F.Mask" "F.Paste")
			(net "CLK_100M_CPU1_CLK05_DP")
		)
	)
)
